# S9S_MB_2U (Grand Teton) — schematic netlist excerpt (pin names and nets, part order shuffled) for the footprints in the layout excerpt that follows; sources: Cadence DE-HDL packaged netlist, KiCad conversion of 03242023_DA0F0TMBIJ0_F0T_Motherboard_J_brd_V01_OCP.brd

PC2002  Q_CAP  0.022UF 16V 10% X7R  pkg 0402  page 299 : A = PVPP_HBM_CPU1_REF ; B = GND
R2676  Q_RES  0 5% CHIP  pkg 0402LF  page 234 : A = SMB_BMC_SWB_EN ; B = SMB_BMC_SWB_EN_R2

(kicad_pcb
	(version 20260206)
	(generator "pcbnew")
	(generator_version "10.0")
	(general
		(thickness 1.6)
		(legacy_teardrops no)
	)
	(paper "A4")
	(title_block
		(title "03242023_DA0F0TMBIJ0_F0T_Motherboard_J_brd_V01_OCP.brd")
		(comment 1 "Grand Teton / footprints 624-625 of 6105")
	)
	(layers
		(0 "F.Cu" signal "TOP")
		(4 "In1.Cu" signal "GND")
		(6 "In2.Cu" signal "IN1")
		(8 "In3.Cu" signal "GND1")
		(10 "In4.Cu" signal "IN2")
		(12 "In5.Cu" signal "GND2")
		(14 "In6.Cu" signal "IN3")
		(16 "In7.Cu" signal "GND3")
		(18 "In8.Cu" signal "VCC")
		(20 "In9.Cu" signal "VCC1")
		(22 "In10.Cu" signal "GND4")
		(24 "In11.Cu" signal "IN4")
		(26 "In12.Cu" signal "GND5")
		(28 "In13.Cu" signal "IN5")
		(30 "In14.Cu" signal "GND6")
		(32 "In15.Cu" signal "IN6")
		(34 "In16.Cu" signal "GND7")
		(2 "B.Cu" signal "BOTTOM")
		(9 "F.Adhes" user "F.Adhesive")
		(11 "B.Adhes" user "B.Adhesive")
		(13 "F.Paste" user "Package Geometry/Pastemask Top")
		(15 "B.Paste" user "Package Geometry/Pastemask Bottom")
		(5 "F.SilkS" user "Ref Des/Silkscreen Top")
		(7 "B.SilkS" user "Ref Des/Silkscreen Bottom")
		(1 "F.Mask" user "Board Geometry/Soldermask Top")
		(3 "B.Mask" user "Board Geometry/Soldermask Bottom")
		(17 "Dwgs.User" user "User.Drawings")
		(19 "Cmts.User" user "User.Comments")
		(21 "Eco1.User" user "User.Eco1")
		(23 "Eco2.User" user "User.Eco2")
		(25 "Edge.Cuts" user "Board Geometry/Outline")
		(27 "Margin" user)
		(31 "F.CrtYd" user "Package Geometry/Place Bound Top")
		(29 "B.CrtYd" user "Package Geometry/Place Bound Bottom")
		(35 "F.Fab" user "Ref Des/Assembly Top")
		(33 "B.Fab" user "Ref Des/Assembly Bottom")
	)
	(footprint ""
		(layer "F.Cu")
		(at 120.975374 -360.043222 90)
		(property "Reference" "PC2002"
			(at 0 0 90)
			(layer "F.SilkS")
			(hide yes)
			(effects
				(font
					(size 1.27 1.27)
				)
			)
		)
		(property "Value" ""
			(at 0 0 90)
			(layer "F.Fab")
			(effects
				(font
					(size 1.27 1.27)
				)
			)
		)
		(duplicate_pad_numbers_are_jumpers no)
		(fp_line
			(start 0.7874 -0.4064)
			(end 0.7874 0.4064)
			(stroke
				(width 0.1524)
				(type default)
			)
			(layer "F.SilkS")
		)
		(fp_line
			(start -0.7874 -0.4064)
			(end 0.7874 -0.4064)
			(stroke
				(width 0.1524)
				(type default)
			)
			(layer "F.SilkS")
		)
		(fp_line
			(start 0.7874 0.4064)
			(end -0.7874 0.4064)
			(stroke
				(width 0.1524)
				(type default)
			)
			(layer "F.SilkS")
		)
		(fp_line
			(start -0.7874 0.4064)
			(end -0.7874 -0.4064)
			(stroke
				(width 0.1524)
				(type default)
			)
			(layer "F.SilkS")
		)
		(fp_line
			(start -0.12065 -0.305054)
			(end -0.12065 -0.2794)
			(stroke
				(width 0.1)
				(type default)
			)
			(layer "F.Fab")
		)
		(fp_line
			(start -0.67945 -0.305054)
			(end -0.12065 -0.305054)
			(stroke
				(width 0.1)
				(type default)
			)
			(layer "F.Fab")
		)
		(fp_line
			(start 0.67945 -0.3048)
			(end 0.67945 0.3048)
			(stroke
				(width 0.1)
				(type default)
			)
			(layer "F.Fab")
		)
		(fp_line
			(start 0.12065 -0.3048)
			(end 0.67945 -0.3048)
			(stroke
				(width 0.1)
				(type default)
			)
			(layer "F.Fab")
		)
		(fp_line
			(start 0.12065 -0.2794)
			(end 0.12065 -0.3048)
			(stroke
				(width 0.1)
				(type default)
			)
			(layer "F.Fab")
		)
		(fp_line
			(start -0.12065 -0.2794)
			(end 0.12065 -0.2794)
			(stroke
				(width 0.1)
				(type default)
			)
			(layer "F.Fab")
		)
		(fp_line
			(start 0.120396 0.2794)
			(end -0.12065 0.2794)
			(stroke
				(width 0.1)
				(type default)
			)
			(layer "F.Fab")
		)
		(fp_line
			(start -0.12065 0.2794)
			(end -0.12065 0.3048)
			(stroke
				(width 0.1)
				(type default)
			)
			(layer "F.Fab")
		)
		(fp_line
			(start 0.67945 0.3048)
			(end 0.120396 0.3048)
			(stroke
				(width 0.1)
				(type default)
			)
			(layer "F.Fab")
		)
		(fp_line
			(start 0.120396 0.3048)
			(end 0.120396 0.2794)
			(stroke
				(width 0.1)
				(type default)
			)
			(layer "F.Fab")
		)
		(fp_line
			(start -0.12065 0.3048)
			(end -0.67945 0.3048)
			(stroke
				(width 0.1)
				(type default)
			)
			(layer "F.Fab")
		)
		(fp_line
			(start -0.67945 0.3048)
			(end -0.67945 -0.305054)
			(stroke
				(width 0.1)
				(type default)
			)
			(layer "F.Fab")
		)
		(pad "1" smd circle
			(at -0.40005 0 90)
			(size 0 0)
			(layers "F.Cu" "F.Mask" "F.Paste")
			(net "PVPP_HBM_CPU1_REF")
		)
		(pad "2" smd circle
			(at 0.40005 0 90)
			(size 0 0)
			(layers "F.Cu" "F.Mask" "F.Paste")
			(net "GND")
		)
	)
	(footprint ""
		(layer "F.Cu")
		(at 357.720392 -400.354038)
		(property "Reference" "R2676"
			(at 0 0 0)
			(layer "F.SilkS")
			(hide yes)
			(effects
				(font
					(size 1.27 1.27)
				)
			)
		)
		(property "Value" ""
			(at 0 0 0)
			(layer "F.Fab")
			(effects
				(font
					(size 1.27 1.27)
				)
			)
		)
		(duplicate_pad_numbers_are_jumpers no)
		(fp_line
			(start -0.7874 -0.4064)
			(end 0.7874 -0.4064)
			(stroke
				(width 0.1524)
				(type default)
			)
			(layer "F.SilkS")
		)
		(fp_line
			(start -0.7874 0.4064)
			(end -0.7874 -0.4064)
			(stroke
				(width 0.1524)
				(type default)
			)
			(layer "F.SilkS")
		)
		(fp_line
			(start 0.7874 -0.4064)
			(end 0.7874 0.4064)
			(stroke
				(width 0.1524)
				(type default)
			)
			(layer "F.SilkS")
		)
		(fp_line
			(start 0.7874 0.4064)
			(end -0.7874 0.4064)
			(stroke
				(width 0.1524)
				(type default)
			)
			(layer "F.SilkS")
		)
		(fp_line
			(start -0.67945 -0.305054)
			(end -0.12065 -0.305054)
			(stroke
				(width 0.1)
				(type default)
			)
			(layer "F.Fab")
		)
		(fp_line
			(start -0.67945 0.3048)
			(end -0.67945 -0.305054)
			(stroke
				(width 0.1)
				(type default)
			)
			(layer "F.Fab")
		)
		(fp_line
			(start -0.12065 -0.305054)
			(end -0.12065 -0.2794)
			(stroke
				(width 0.1)
				(type default)
			)
			(layer "F.Fab")
		)
		(fp_line
			(start -0.12065 -0.2794)
			(end 0.12065 -0.2794)
			(stroke
				(width 0.1)
				(type default)
			)
			(layer "F.Fab")
		)
		(fp_line
			(start -0.12065 0.2794)
			(end -0.12065 0.3048)
			(stroke
				(width 0.1)
				(type default)
			)
			(layer "F.Fab")
		)
		(fp_line
			(start -0.12065 0.3048)
			(end -0.67945 0.3048)
			(stroke
				(width 0.1)
				(type default)
			)
			(layer "F.Fab")
		)
		(fp_line
			(start 0.120396 0.2794)
			(end -0.12065 0.2794)
			(stroke
				(width 0.1)
				(type default)
			)
			(layer "F.Fab")
		)
		(fp_line
			(start 0.120396 0.3048)
			(end 0.120396 0.2794)
			(stroke
				(width 0.1)
				(type default)
			)
			(layer "F.Fab")
		)
		(fp_line
			(start 0.12065 -0.3048)
			(end 0.67945 -0.3048)
			(stroke
				(width 0.1)
				(type default)
			)
			(layer "F.Fab")
		)
		(fp_line
			(start 0.12065 -0.2794)
			(end 0.12065 -0.3048)
			(stroke
				(width 0.1)
				(type default)
			)
			(layer "F.Fab")
		)
		(fp_line
			(start 0.67945 -0.3048)
			(end 0.67945 0.3048)
			(stroke
				(width 0.1)
				(type default)
			)
			(layer "F.Fab")
		)
		(fp_line
			(start 0.67945 0.3048)
			(end 0.120396 0.3048)
			(stroke
				(width 0.1)
				(type default)
			)
			(layer "F.Fab")
		)
		(pad "1" smd circle
			(at -0.40005 0)
			(size 0 0)
			(layers "F.Cu" "F.Mask" "F.Paste")
			(net "SMB_BMC_SWB_EN")
		)
		(pad "2" smd circle
			(at 0.40005 0)
			(size 0 0)
			(layers "F.Cu" "F.Mask" "F.Paste")
			(net "SMB_BMC_SWB_EN_R2")
		)
	)
)
